# T6G (Grand Teton) — schematic parts with pin connectivity, parts 2617–2626 of 8303; source: Cadence DE-HDL packaged netlist (pstxprt.dat, pstxnet.dat, pstchip.dat)

J45  CONN60_101062636003K02LF  CONN60_10106263-6003K02LF IO  pkg HSD_M60D4H2D_P2-54W2-54_LDHXB  page 240
  A1  A1  BI  = TP_J45_A1
  A2  A2  BI  = FM_AC_PWR_BTN_PDB_N
  A3  A3  BI  = P3V3_PDB_AUX_ADC
  B1  B1  BI  = RST_SMB_SWITCH_R_N
  B2  B2  BI  = PWRGD_P3V3_AUX_PDB_BUF
  B3  B3  BI  = GND
  C1  C1  BI  = SMB_FAN_3V3AUX_BUF_R_SCL
  C2  C2  BI  = SMB_FAN_3V3AUX_BUF_R_SDA
  C3  C3  BI  = HPDB_HSC_PWRGD_R
  D1  D1  BI  = FM_FAN_PWR_EN_R
  D2  D2  BI  = FM_GPU_HSC_EN_BUF_R1
  D3  D3  BI  = PDB_PRSNT_N
  P1_1  P1_1  POWER  = GND
  P1_2  P1_2  POWER  = GND
  P1_3  P1_3  POWER  = GND
  P1_4  P1_4  POWER  = GND
  P1_5  P1_5  POWER  = GND
  P1_6  P1_6  POWER  = GND
  P1_7  P1_7  POWER  = GND
  P1_8  P1_8  POWER  = GND
  P2_1  P2_1  POWER  = GND
  P2_2  P2_2  POWER  = GND
  P2_3  P2_3  POWER  = GND
  P2_4  P2_4  POWER  = GND
  P2_5  P2_5  POWER  = GND
  P2_6  P2_6  POWER  = GND
  P2_7  P2_7  POWER  = GND
  P2_8  P2_8  POWER  = GND
  P3_1  P3_1  POWER  = GND
  P3_2  P3_2  POWER  = GND
  P3_3  P3_3  POWER  = GND
  P3_4  P3_4  POWER  = GND
  P3_5  P3_5  POWER  = GND
  P3_6  P3_6  POWER  = GND
  P3_7  P3_7  POWER  = GND
  P3_8  P3_8  POWER  = GND
  P4_1  P4_1  POWER  = P12V_PSU
  P4_2  P4_2  POWER  = P12V_PSU
  P4_3  P4_3  POWER  = P12V_PSU
  P4_4  P4_4  POWER  = P12V_PSU
  P4_5  P4_5  POWER  = P12V_PSU
  P4_6  P4_6  POWER  = P12V_PSU
  P4_7  P4_7  POWER  = P12V_PSU
  P4_8  P4_8  POWER  = P12V_PSU
  P5_1  P5_1  POWER  = P12V_PSU
  P5_2  P5_2  POWER  = P12V_PSU
  P5_3  P5_3  POWER  = P12V_PSU
  P5_4  P5_4  POWER  = P12V_PSU
  P5_5  P5_5  POWER  = P12V_PSU
  P5_6  P5_6  POWER  = P12V_PSU
  P5_7  P5_7  POWER  = P12V_PSU
  P5_8  P5_8  POWER  = P12V_PSU
  P6_1  P6_1  POWER  = P12V_PSU
  P6_2  P6_2  POWER  = P12V_PSU
  P6_3  P6_3  POWER  = P12V_PSU
  P6_4  P6_4  POWER  = P12V_PSU
  P6_5  P6_5  POWER  = P12V_PSU
  P6_6  P6_6  POWER  = P12V_PSU
  P6_7  P6_7  POWER  = P12V_PSU
  P6_8  P6_8  POWER  = P12V_PSU

J48  SCONN8_G802M0083150RD3HR  IO  pkg HEADER2X4SXN  page 27
  1  \1\  BI  = CPU0_BP0
  2  \2\  BI  = GND
  3  \3\  BI  = CPU0_BP1
  4  \4\  BI  = GND
  5  \5\  BI  = CPU0_BP2
  6  \6\  BI  = GND
  7  \7\  BI  = CPU0_BP3
  8  \8\  BI  = GND

J49  SCONN8_G802M0083150RD3HR  IO  pkg HEADER2X4SXN  page 54
  1  \1\  BI  = CPU1_BP0
  2  \2\  BI  = GND
  3  \3\  BI  = CPU1_BP1
  4  \4\  BI  = GND
  5  \5\  BI  = CPU1_BP2
  6  \6\  BI  = GND
  7  \7\  BI  = CPU1_BP3
  8  \8\  BI  = GND

J54  SCONN20_HSU2101L00007H  SCONN20_HSU2101-L0000-7H IO  pkg HEADER2X10SXK  page 172
  1  \1\  BI  = PVDD18_S5_P0
  2  \2\  BI  = HDT_HDR_R_TCK
  3  \3\  BI  = PRSNT_HDT_R_N
  4  \4\  BI  = HDT_HDR_R_TMS
  5  \5\  BI  = GND
  6  \6\  BI  = HDT_HDR_R_TDI
  7  \7\  BI  = GND
  8  \8\  BI  = HDT_HDR_TDO
  9  \9\  BI  = HDT_HDR_TRST_N_R
  10  \10\  BI  = HDT_HDR_PWROK
  11  \11\  BI  = HDT_CPU0_XTRIG_L6
  12  \12\  BI  = HDT_HDR_RESET_N
  13  \13\  BI  = HDT_CPU0_XTRIG_L7
  14  \14\  BI  = NC
  15  \15\  BI  = HDT_CPU0_XTRIG_L5
  16  \16\  BI  = HDT_HDR_DBREQ_R_N
  17  \17\  BI  = GND
  18  \18\  BI  = HDT_CPU0_HDT_CONN_TESTEN
  19  \19\  BI  = PVDD18_S5_P0
  20  \20\  BI  = NC

J57  CONN8_HBB1081L200D8H  CONN8_HBB1081-L200D-8H IO  pkg HEADER1X8XA_H340  page 85
  1  \1\  BI  = P3V3_AUX
  2  \2\  BI  = JTAG_PLD_TDI
  3  \3\  BI  = JTAG_PLD_TDO
  4  \4\  BI  = NC
  5  \5\  BI  = NC
  6  \6\  BI  = JTAG_PLD_TMS
  7  \7\  BI  = GND
  8  \8\  BI  = JTAG_PLD_TCK

J59  SCONN75K_APCI0155P004A  SCONN75K_APCI0155-P004A EMPTY  pkg CON_F67S2H2D2S_P0-5W7-55_LUVXB_H270  page 144
  1  GND1  POWER  = PCIE_M2_SSD0_PRSNT_N
  2  \3.3v_1\  POWER  = P3V3_M2_0
  3  GND2  POWER  = GND
  4  \3.3v_2\  POWER  = P3V3_M2_0
  5  PERN3  BI  = P3E_CPU1_P4_RX_DN<3>
  6  NC1  TRI  = NC_M2_0_NC1
  7  PERP3  BI  = P3E_CPU1_P4_RX_DP<3>
  8  NC2  TRI  = NC_M2_0_NC2
  9  GND3  POWER  = GND
  10  \das_dss#||led1#\  BI  = LED_M2_SSD_0_ACT_N
  11  PETN3  BI  = P3E_CPU1_P4_TX_C_DN<3>
  12  \3.3v_3\  POWER  = P3V3_M2_0
  13  PETP3  BI  = P3E_CPU1_P4_TX_C_DP<3>
  14  \3.3v_4\  POWER  = P3V3_M2_0
  15  GND4  POWER  = GND
  16  \3.3v_5\  POWER  = P3V3_M2_0
  17  PERN2  BI  = P3E_CPU1_P4_RX_DN<2>
  18  \3.3v_6\  POWER  = P3V3_M2_0
  19  PERP2  BI  = P3E_CPU1_P4_RX_DP<2>
  20  NC3  TRI  = NC_M2_0_NC3
  21  GND5  POWER  = GND
  22  NC4  TRI  = NC_M2_0_NC4
  23  PETN2  BI  = P3E_CPU1_P4_TX_C_DN<2>
  24  NC5  TRI  = NC_M2_0_NC5
  25  PETP2  BI  = P3E_CPU1_P4_TX_C_DP<2>
  26  NC6  TRI  = NC_M2_0_NC6
  27  GND6  POWER  = GND
  28  NC7  TRI  = NC_M2_0_NC7
  29  PERN1  BI  = P3E_CPU1_P4_RX_DN<1>
  30  NC8  TRI  = NC_M2_0_NC8
  31  PERP1  BI  = P3E_CPU1_P4_RX_DP<1>
  32  NC9  TRI  = NC_M2_0_NC9
  33  GND7  POWER  = GND
  34  NC10  TRI  = NC_M2_0_NC10
  35  PETN1  BI  = P3E_CPU1_P4_TX_C_DN<1>
  36  NC11  TRI  = NC_M2_0_NC11
  37  PETP1  BI  = P3E_CPU1_P4_TX_C_DP<1>
  38  DEVSLP  IN  = PD_M2_0_DEVSLP
  39  GND8  POWER  = GND
  40  NC12  TRI  = SMB_M2_P1_1V8AUX_SCL
  41  \pern0||sata-b+\  BI  = P3E_CPU1_P4_RX_DN<0>
  42  NC13  TRI  = SMB_M2_P1_1V8AUX_SDA
  43  \perp0||sata-b-\  BI  = P3E_CPU1_P4_RX_DP<0>
  44  NC14  TRI  = NC_M2_0_NC14
  45  GND9  POWER  = GND
  46  NC15  TRI  = NC_M2_0_NC15
  47  \petn0||sata-a-\  BI  = P3E_CPU1_P4_TX_C_DN<0>
  48  NC16  TRI  = NC_M2_0_NC16
  49  \petp0||sata-a+\  BI  = P3E_CPU1_P4_TX_C_DP<0>
  50  \perst#\  IN  = RST_PERST_BUF_M2_0_R_N
  51  GND10  POWER  = GND
  52  \clkreq#\  BI  = M2_SSD0_CLKREQ_EN_N_BUF
  53  REFCLKN  IN  = CLK_100M_CPU1_CLK12_DN
  54  \pewake#\  BI  = M2_0_PEWAKE_N
  55  REFCLKP  IN  = CLK_100M_CPU1_CLK12_DP
  56  NC17  TRI  = NC_M2_0_NC17
  57  GND11  POWER  = GND
  58  NC18  TRI  = NC_M2_0_NC18
  67  NC19  TRI  = NC_M2_0_NC19
  68  SUSCLK  IN  = NC_M2_0_SUSCLK
  69  PEDET  OUT  = FM_M2_SSD_0_PEDET
  70  \3.3v_7\  POWER  = P3V3_M2_0
  71  GND12  POWER  = GND
  72  \3.3v_8\  POWER  = P3V3_M2_0
  73  GND13  POWER  = GND
  74  \3.3v_9\  POWER  = P3V3_M2_0
  75  GND14  POWER  = GND
  G1  G1  POWER  = GND
  G2  G2  POWER  = GND

J63  PICOPROBE_BXA  DELTA-L 4.0 EMPTY  pkg TRIANG_LAUNCH_3PXB  page 229
  1  \1_p\  POWER  = DELTA_L_85_5INCH_TOP_DP
  2  \2_n\  POWER  = DELTA_L_85_5INCH_TOP_DN
  3  \3_g\  POWER  = DELTA_L_GND_1

J64  PICOPROBE_BXA  DELTA-L 4.0 EMPTY  pkg TRIANG_LAUNCH_3PXB  page 229
  1  \1_p\  POWER  = DELTA_L_85_5INCH_BOT_DP
  2  \2_n\  POWER  = DELTA_L_85_5INCH_BOT_DN
  3  \3_g\  POWER  = DELTA_L_GND_1

J65  PICOPROBE_BXA  DELTA-L 4.0 EMPTY  pkg TRIANG_LAUNCH_3PXB  page 229
  1  \1_p\  POWER  = DELTA_L_85_5INCH_IN1_DP
  2  \2_n\  POWER  = DELTA_L_85_5INCH_IN1_DN
  3  \3_g\  POWER  = DELTA_L_GND_1

J66  PICOPROBE_BXA  DELTA-L 4.0 EMPTY  pkg TRIANG_LAUNCH_3PXB  page 229
  1  \1_p\  POWER  = DELTA_L_85_5INCH_IN2_DP
  2  \2_n\  POWER  = DELTA_L_85_5INCH_IN2_DN
  3  \3_g\  POWER  = DELTA_L_GND_1
